FILE_TYPE = CONNECTIVITY;
{Allegro Design Entry HDL 17.4-2019 S026 (4007227) 1/17/2022}
"PAGE_NUMBER" = 154;
0"NC";
1"P1V2_AUX\g";
2"P1V2_AUX\g";
3"GND\g";
4"P1V2_AUX\g";
5"P1V2_AUX\g";
6"GND\g";
7"GND\g";
8"GND\g";
9"GND\g";
10"GND\g";
11"GND\g";
12"GND\g";
13"GND\g";
14"GND\g";
15"GND\g";
16"GND\g";
17"GND\g";
18"GND\g";
19"P3V3_AUX_CPU0_USB_AVDD33\g";
20"GND\g";
21"GND\g";
22"GND\g";
23"P1V2_CPU0_USB_DVDD12\g";
24"GND\g";
25"GND\g";
26"GND\g";
27"P3V3_AUX\g";
28"GND\g";
29"GND\g";
30"GND\g";
31"GND\g";
%"CYUSB330468LTXI"
"2","(-4700,3600)","0","pure_quanta","I1";
;
LOCATION"U6001"
$SEC"2"
CDS_SEC"2"
VALUE"CYUSB3304-68LTXI"
MATERIAL"IC"
PART_TYPE"SMLF"
ROOM"USB3_HUB1_CYP"
NEEDS_NO_SIZE"TRUE"
CDS_LMAN_SYM_OUTLINE"-575,1950,575,-1950"
CDS_LIB"pure_quanta"
PART_NUMBER"AJ033040001";
"AVDD12_5"
$PN"52"4;
"AVDD12_4"
$PN"46"4;
"AVDD12_3"
$PN"34"4;
"AVDD12_2"
$PN"16"4;
"AVDD12_1"
$PN"10"4;
"VDD_IO"
$PN"28"27;
"AVDD33_4"
$PN"66"27;
"AVDD33_3"
$PN"61"27;
"AVDD33_2"
$PN"56"27;
"AVDD33_1"
$PN"4"19;
"DVDD12_7"
$PN"37"5;
"DVDD12_6"
$PN"13"5;
"DVDD12_5"
$PN"7"5;
"AVDD12_6"
$PN"53"2;
"DVDD12_4"
$PN"49"5;
"DVDD12_8"
$PN"43"5;
"DVDD12_3"
$PN"27"23;
"VDD_EFUSE"
$PN"19"23;
"DVDD12_2"
$PN"3"23;
"DVDD12_1"
$PN"1"23;
%"Q_CAP"
"1","(-6975,3200)","0","pure_quanta","I10";
;
LOCATION"C6043"
$SEC"1"
CDS_SEC"1"
ROOM"USB3_HUB1_CYP"
VALUE"1UF"
PACK_TYPE"C0402"
MATERIAL"X6S"
VOLTAGE"25V"
TOLERANCE"10%"
CDS_LIB"pure_quanta"
PART_NUMBER"CH5104KEB02";
"B"
$PN"2"30;
"A"
$PN"1"19;
%"GND"
"1","(-6975,2825)","0","pure_quanta_power","I11";
;
SIZE"1B"
CDS_LIB"pure_quanta_power"
HDL_POWER"GND";
"A<SIZE-1..0>\NAC"30;
%"Q_CAP"
"1","(-6450,3225)","0","pure_quanta","I12";
;
LOCATION"C6044"
$SEC"1"
CDS_SEC"1"
VOLTAGE"25V"
TOLERANCE"10%"
VALUE"0.1UF"
MATERIAL"X7R"
PACK_TYPE"0402"
ROOM"USB3_HUB1_CYP"
CDS_LIB"pure_quanta"
PART_NUMBER"CH4104K1B00";
"B"
$PN"2"30;
"A"
$PN"1"19;
%"Q_CAP"
"1","(-5950,3200)","0","pure_quanta","I13";
;
LOCATION"C6045"
$SEC"1"
CDS_SEC"1"
ROOM"USB3_HUB1_CYP"
PACK_TYPE"C0402"
VALUE"0.01UF"
VOLTAGE"50V"
TOLERANCE"10%"
MATERIAL"X7R"
CDS_LIB"pure_quanta"
PART_NUMBER"CH31006KB18";
"B"
$PN"2"30;
"A"
$PN"1"19;
%"Q_CAP"
"1","(-8350,2225)","2","pure_quanta","I14";
;
LOCATION"C6046"
$SEC"1"
CDS_SEC"1"
MATERIAL"X6S"
TOLERANCE"20%"
VOLTAGE"6.3V"
PACK_TYPE"C0603"
VALUE"22UF"
ROOM"USB3_HUB1_CYP"
CDS_LIB"pure_quanta"
PART_NUMBER"CH6221ME900";
"B"
$PN"2"29;
"A"
$PN"1"27;
%"Q_CAP"
"1","(-8150,2225)","0","pure_quanta","I15";
;
LOCATION"C6047"
$SEC"1"
CDS_SEC"1"
PACK_TYPE"C0402"
VOLTAGE"25V"
TOLERANCE"10%"
MATERIAL"X6S"
VALUE"1UF"
ROOM"USB3_HUB1_CYP"
CDS_LIB"pure_quanta"
PART_NUMBER"CH5104KEB02";
"B"
$PN"2"29;
"A"
$PN"1"27;
%"GND"
"1","(-8200,1750)","0","pure_quanta_power","I16";
;
CDS_LIB"pure_quanta_power"
SIZE"1B"
HDL_POWER"GND";
"A<SIZE-1..0>\NAC"29;
%"Q_CAP"
"1","(-7525,2125)","0","pure_quanta","I17";
;
LOCATION"C6048"
$SEC"1"
CDS_SEC"1"
ROOM"USB3_HUB1_CYP"
VALUE"0.1UF"
MATERIAL"X7R"
VOLTAGE"25V"
TOLERANCE"10%"
PACK_TYPE"0402"
CDS_LIB"pure_quanta"
PART_NUMBER"CH4104K1B00";
"B"
$PN"2"28;
"A"
$PN"1"27;
%"GND"
"1","(-7525,1775)","0","pure_quanta_power","I18";
;
SIZE"1B"
CDS_LIB"pure_quanta_power"
HDL_POWER"GND";
"A<SIZE-1..0>\NAC"28;
%"Q_CAP"
"1","(-7175,2125)","0","pure_quanta","I19";
;
LOCATION"C6049"
$SEC"1"
CDS_SEC"1"
VOLTAGE"50V"
MATERIAL"X7R"
TOLERANCE"10%"
VALUE"0.01UF"
PACK_TYPE"C0402"
ROOM"USB3_HUB1_CYP"
CDS_LIB"pure_quanta"
PART_NUMBER"CH31006KB18";
"B"
$PN"2"28;
"A"
$PN"1"27;
%"UNIVERSAL_POWER"
"1","(-8400,4250)","0","pure_quanta_power","I2";
;
HDL_POWER"P3V3_AUX"
BOM_COST"VR_SYSTEM"
CDS_LIB"pure_quanta_power";
"A"27;
%"Q_CAP"
"1","(-6725,2125)","0","pure_quanta","I20";
;
LOCATION"C6050"
$SEC"1"
CDS_SEC"1"
ROOM"USB3_HUB1_CYP"
PACK_TYPE"0402"
VALUE"0.1UF"
VOLTAGE"25V"
MATERIAL"X7R"
TOLERANCE"10%"
CDS_LIB"pure_quanta"
PART_NUMBER"CH4104K1B00";
"B"
$PN"2"26;
"A"
$PN"1"27;
%"Q_CAP"
"1","(-6400,2125)","0","pure_quanta","I21";
;
LOCATION"C6051"
$SEC"1"
CDS_SEC"1"
ROOM"USB3_HUB1_CYP"
TOLERANCE"10%"
MATERIAL"X7R"
PACK_TYPE"C0402"
VOLTAGE"50V"
VALUE"0.01UF"
CDS_LIB"pure_quanta"
PART_NUMBER"CH31006KB18";
"B"
$PN"2"26;
"A"
$PN"1"27;
%"Q_CAP"
"1","(-5725,2125)","0","pure_quanta","I22";
;
LOCATION"C6053"
$SEC"1"
CDS_SEC"1"
VOLTAGE"50V"
PACK_TYPE"C0402"
MATERIAL"X7R"
TOLERANCE"10%"
VALUE"0.01UF"
ROOM"USB3_HUB1_CYP"
CDS_LIB"pure_quanta"
PART_NUMBER"CH31006KB18";
"B"
$PN"2"25;
"A"
$PN"1"27;
%"Q_CAP"
"1","(-6025,2125)","0","pure_quanta","I23";
;
LOCATION"C6052"
$SEC"1"
CDS_SEC"1"
ROOM"USB3_HUB1_CYP"
VALUE"0.1UF"
MATERIAL"X7R"
TOLERANCE"10%"
VOLTAGE"25V"
PACK_TYPE"0402"
CDS_LIB"pure_quanta"
PART_NUMBER"CH4104K1B00";
"B"
$PN"2"25;
"A"
$PN"1"27;
%"GND"
"1","(-6725,1750)","0","pure_quanta_power","I24";
;
SIZE"1B"
CDS_LIB"pure_quanta_power"
HDL_POWER"GND";
"A<SIZE-1..0>\NAC"26;
%"GND"
"1","(-6025,1775)","0","pure_quanta_power","I25";
;
CDS_LIB"pure_quanta_power"
SIZE"1B"
HDL_POWER"GND";
"A<SIZE-1..0>\NAC"25;
%"Q_INDUCTOR"
"1","(-8400,5475)","0","pure_quanta","I26";
;
LOCATION"L6001"
$SEC"1"
CDS_SEC"1"
ROOM"USB3_HUB1_CYP"
PACK_TYPE"SMLF"
MATERIAL"IND"
VALUE"BLM21PG221SN1D"
NEEDS_NO_SIZE"TRUE"
CDS_LIB"pure_quanta"
PART_NUMBER"CX1PG221001";
"1"
$PN"1"1;
"2"
$PN"2"23;
%"Q_CAP"
"1","(-8200,5250)","2","pure_quanta","I27";
;
LOCATION"C6030"
$SEC"1"
CDS_SEC"1"
ROOM"USB3_HUB1_CYP"
TOLERANCE"20%"
MATERIAL"X6S"
PACK_TYPE"C0603"
VALUE"22UF"
VOLTAGE"6.3V"
CDS_LIB"pure_quanta"
PART_NUMBER"CH6221ME900";
"B"
$PN"2"24;
"A"
$PN"1"23;
%"GND"
"1","(-7975,4875)","0","pure_quanta_power","I28";
;
SIZE"1B"
CDS_LIB"pure_quanta_power"
HDL_POWER"GND";
"A<SIZE-1..0>\NAC"24;
%"Q_CAP"
"1","(-7975,5250)","0","pure_quanta","I29";
;
LOCATION"C6031"
$SEC"1"
CDS_SEC"1"
ROOM"USB3_HUB1_CYP"
PACK_TYPE"C0402"
TOLERANCE"10%"
MATERIAL"X6S"
VALUE"1UF"
VOLTAGE"25V"
CDS_LIB"pure_quanta"
PART_NUMBER"CH5104KEB02";
"B"
$PN"2"24;
"A"
$PN"1"23;
%"Q_INDUCTOR"
"1","(-8100,3425)","0","pure_quanta","I3";
;
LOCATION"L6000"
$SEC"1"
CDS_SEC"1"
PACK_TYPE"SMLF"
VALUE"BLM21PG221SN1D"
MATERIAL"IND"
ROOM"USB3_HUB1_CYP"
NEEDS_NO_SIZE"TRUE"
CDS_LIB"pure_quanta"
PART_NUMBER"CX1PG221001";
"1"
$PN"1"27;
"2"
$PN"2"19;
%"UNIVERSAL_POWER"
"1","(-7875,5825)","0","pure_quanta_power","I30";
;
HDL_POWER"P1V2_CPU0_USB_DVDD12"
BOM_COST"VR_SYSTEM"
CDS_LIB"pure_quanta_power";
"A"23;
%"Q_CAP"
"1","(-6725,4900)","0","pure_quanta","I31";
;
LOCATION"C6035"
$SEC"1"
CDS_SEC"1"
PACK_TYPE"C0402"
ROOM"USB3_HUB1_CYP"
TOLERANCE"10%"
MATERIAL"X7R"
VOLTAGE"50V"
VALUE"0.01UF"
CDS_LIB"pure_quanta"
PART_NUMBER"CH31006KB18";
"B"
$PN"2"22;
"A"
$PN"1"23;
%"Q_CAP"
"1","(-6950,4925)","0","pure_quanta","I32";
;
LOCATION"C6034"
$SEC"1"
CDS_SEC"1"
PACK_TYPE"0402"
ROOM"USB3_HUB1_CYP"
TOLERANCE"10%"
VALUE"0.1UF"
VOLTAGE"25V"
MATERIAL"X7R"
CDS_LIB"pure_quanta"
PART_NUMBER"CH4104K1B00";
"B"
$PN"2"22;
"A"
$PN"1"23;
%"GND"
"1","(-6775,4525)","0","pure_quanta_power","I33";
;
CDS_LIB"pure_quanta_power"
SIZE"1B"
HDL_POWER"GND";
"A<SIZE-1..0>\NAC"22;
%"Q_CAP"
"1","(-7225,4925)","0","pure_quanta","I34";
;
LOCATION"C6033"
$SEC"1"
CDS_SEC"1"
VALUE"0.01UF"
MATERIAL"X7R"
TOLERANCE"10%"
ROOM"USB3_HUB1_CYP"
PACK_TYPE"C0402"
VOLTAGE"50V"
CDS_LIB"pure_quanta"
PART_NUMBER"CH31006KB18";
"B"
$PN"2"21;
"A"
$PN"1"23;
%"Q_CAP"
"1","(-7475,4925)","0","pure_quanta","I35";
;
LOCATION"C6032"
$SEC"1"
CDS_SEC"1"
VOLTAGE"25V"
TOLERANCE"10%"
PACK_TYPE"0402"
MATERIAL"X7R"
ROOM"USB3_HUB1_CYP"
VALUE"0.1UF"
CDS_LIB"pure_quanta"
PART_NUMBER"CH4104K1B00";
"B"
$PN"2"21;
"A"
$PN"1"23;
%"GND"
"1","(-7475,4575)","0","pure_quanta_power","I36";
;
CDS_LIB"pure_quanta_power"
SIZE"1B"
HDL_POWER"GND";
"A<SIZE-1..0>\NAC"21;
%"Q_CAP"
"1","(-6450,4925)","0","pure_quanta","I37";
;
LOCATION"C6036"
$SEC"1"
CDS_SEC"1"
PACK_TYPE"0402"
ROOM"USB3_HUB1_CYP"
MATERIAL"X7R"
VOLTAGE"25V"
TOLERANCE"10%"
VALUE"0.1UF"
CDS_LIB"pure_quanta"
PART_NUMBER"CH4104K1B00";
"B"
$PN"2"20;
"A"
$PN"1"23;
%"Q_CAP"
"1","(-6225,4925)","0","pure_quanta","I38";
;
LOCATION"C6037"
$SEC"1"
CDS_SEC"1"
VOLTAGE"50V"
VALUE"0.01UF"
TOLERANCE"10%"
MATERIAL"X7R"
PACK_TYPE"C0402"
ROOM"USB3_HUB1_CYP"
CDS_LIB"pure_quanta"
PART_NUMBER"CH31006KB18";
"B"
$PN"2"20;
"A"
$PN"1"23;
%"GND"
"1","(-6450,4550)","0","pure_quanta_power","I39";
;
SIZE"1B"
CDS_LIB"pure_quanta_power"
HDL_POWER"GND";
"A<SIZE-1..0>\NAC"20;
%"UNIVERSAL_POWER"
"1","(-7525,3875)","0","pure_quanta_power","I4";
;
HDL_POWER"P3V3_AUX_CPU0_USB_AVDD33"
BOM_COST"VR_SYSTEM"
CDS_LIB"pure_quanta_power";
"A"19;
%"Q_CAP"
"1","(-5650,4900)","0","pure_quanta","I40";
;
LOCATION"C6039"
$SEC"1"
CDS_SEC"1"
VOLTAGE"50V"
TOLERANCE"10%"
MATERIAL"X7R"
ROOM"USB3_HUB1_CYP"
PACK_TYPE"C0402"
VALUE"0.01UF"
CDS_LIB"pure_quanta"
PART_NUMBER"CH31006KB18";
"B"
$PN"2"18;
"A"
$PN"1"23;
%"Q_CAP"
"1","(-5875,4900)","0","pure_quanta","I41";
;
LOCATION"C6038"
$SEC"1"
CDS_SEC"1"
PACK_TYPE"0402"
VALUE"0.1UF"
VOLTAGE"25V"
TOLERANCE"10%"
MATERIAL"X7R"
ROOM"USB3_HUB1_CYP"
CDS_LIB"pure_quanta"
PART_NUMBER"CH4104K1B00";
"B"
$PN"2"18;
"A"
$PN"1"23;
%"GND"
"1","(-5875,4525)","0","pure_quanta_power","I42";
;
CDS_LIB"pure_quanta_power"
SIZE"1B"
HDL_POWER"GND";
"A<SIZE-1..0>\NAC"18;
%"Q_CAP"
"1","(-3750,4850)","0","pure_quanta","I43";
;
LOCATION"C6054"
$SEC"1"
CDS_SEC"1"
PACK_TYPE"C0402"
TOLERANCE"10%"
VOLTAGE"50V"
VALUE"0.001UF"
MATERIAL"X7R"
ROOM"USB3_HUB1_CYP"
CDS_LIB"pure_quanta"
PART_NUMBER"CH30106KB19";
"B"
$PN"2"17;
"A"
$PN"1"5;
%"Q_CAP"
"1","(-3500,4850)","0","pure_quanta","I44";
;
LOCATION"C6055"
$SEC"1"
CDS_SEC"1"
PACK_TYPE"C0402"
TOLERANCE"10%"
MATERIAL"X7R"
VOLTAGE"50V"
VALUE"0.01UF"
ROOM"USB3_HUB1_CYP"
CDS_LIB"pure_quanta"
PART_NUMBER"CH31006KB18";
"B"
$PN"2"17;
"A"
$PN"1"5;
%"GND"
"1","(-3700,4525)","0","pure_quanta_power","I45";
;
SIZE"1B"
CDS_LIB"pure_quanta_power"
HDL_POWER"GND";
"A<SIZE-1..0>\NAC"17;
%"Q_CAP"
"1","(-3250,4850)","0","pure_quanta","I46";
;
LOCATION"C6056"
$SEC"1"
CDS_SEC"1"
MATERIAL"X7R"
TOLERANCE"10%"
PACK_TYPE"C0402"
VALUE"0.001UF"
VOLTAGE"50V"
ROOM"USB3_HUB1_CYP"
CDS_LIB"pure_quanta"
PART_NUMBER"CH30106KB19";
"B"
$PN"2"16;
"A"
$PN"1"5;
%"Q_CAP"
"1","(-3000,4850)","0","pure_quanta","I47";
;
LOCATION"C6057"
$SEC"1"
CDS_SEC"1"
TOLERANCE"10%"
PACK_TYPE"C0402"
VOLTAGE"50V"
MATERIAL"X7R"
ROOM"USB3_HUB1_CYP"
VALUE"0.01UF"
CDS_LIB"pure_quanta"
PART_NUMBER"CH31006KB18";
"B"
$PN"2"16;
"A"
$PN"1"5;
%"GND"
"1","(-3200,4525)","0","pure_quanta_power","I48";
;
SIZE"1B"
CDS_LIB"pure_quanta_power"
HDL_POWER"GND";
"A<SIZE-1..0>\NAC"16;
%"Q_CAP"
"1","(-2650,4850)","0","pure_quanta","I49";
;
LOCATION"C6058"
$SEC"1"
CDS_SEC"1"
VALUE"0.001UF"
VOLTAGE"50V"
MATERIAL"X7R"
TOLERANCE"10%"
PACK_TYPE"C0402"
ROOM"USB3_HUB1_CYP"
CDS_LIB"pure_quanta"
PART_NUMBER"CH30106KB19";
"B"
$PN"2"15;
"A"
$PN"1"5;
%"Q_CAP"
"1","(-6850,3900)","0","pure_quanta","I5";
;
LOCATION"C6040"
$SEC"1"
CDS_SEC"1"
PACK_TYPE"C0402"
VOLTAGE"50V"
TOLERANCE"10%"
VALUE"0.01UF"
ROOM"USB3_HUB1_CYP"
MATERIAL"X7R"
CDS_LIB"pure_quanta"
PART_NUMBER"CH31006KB18";
"B"
$PN"2"7;
"A"
$PN"1"27;
%"Q_CAP"
"1","(-2400,4850)","0","pure_quanta","I50";
;
LOCATION"C6059"
$SEC"1"
CDS_SEC"1"
MATERIAL"X7R"
PACK_TYPE"C0402"
VALUE"0.01UF"
TOLERANCE"10%"
VOLTAGE"50V"
ROOM"USB3_HUB1_CYP"
CDS_LIB"pure_quanta"
PART_NUMBER"CH31006KB18";
"B"
$PN"2"15;
"A"
$PN"1"5;
%"GND"
"1","(-2600,4525)","0","pure_quanta_power","I51";
;
SIZE"1B"
CDS_LIB"pure_quanta_power"
HDL_POWER"GND";
"A<SIZE-1..0>\NAC"15;
%"Q_CAP"
"1","(-2025,4850)","0","pure_quanta","I52";
;
LOCATION"C6060"
$SEC"1"
CDS_SEC"1"
VALUE"0.001UF"
VOLTAGE"50V"
TOLERANCE"10%"
MATERIAL"X7R"
PACK_TYPE"C0402"
ROOM"USB3_HUB1_CYP"
CDS_LIB"pure_quanta"
PART_NUMBER"CH30106KB19";
"B"
$PN"2"14;
"A"
$PN"1"5;
%"Q_CAP"
"1","(-1775,4850)","0","pure_quanta","I53";
;
LOCATION"C6061"
$SEC"1"
CDS_SEC"1"
ROOM"USB3_HUB1_CYP"
PACK_TYPE"C0402"
VALUE"0.01UF"
VOLTAGE"50V"
TOLERANCE"10%"
MATERIAL"X7R"
CDS_LIB"pure_quanta"
PART_NUMBER"CH31006KB18";
"B"
$PN"2"14;
"A"
$PN"1"5;
%"GND"
"1","(-1975,4525)","0","pure_quanta_power","I54";
;
SIZE"1B"
CDS_LIB"pure_quanta_power"
HDL_POWER"GND";
"A<SIZE-1..0>\NAC"14;
%"Q_CAP"
"1","(-1425,4850)","0","pure_quanta","I55";
;
LOCATION"C6062"
$SEC"1"
CDS_SEC"1"
ROOM"USB3_HUB1_CYP"
TOLERANCE"10%"
VOLTAGE"50V"
MATERIAL"X7R"
PACK_TYPE"C0402"
VALUE"0.001UF"
CDS_LIB"pure_quanta"
PART_NUMBER"CH30106KB19";
"B"
$PN"2"13;
"A"
$PN"1"5;
%"Q_CAP"
"1","(-1175,4850)","0","pure_quanta","I56";
;
LOCATION"C6063"
$SEC"1"
CDS_SEC"1"
ROOM"USB3_HUB1_CYP"
PACK_TYPE"C0402"
VALUE"0.01UF"
VOLTAGE"50V"
TOLERANCE"10%"
MATERIAL"X7R"
CDS_LIB"pure_quanta"
PART_NUMBER"CH31006KB18";
"B"
$PN"2"13;
"A"
$PN"1"5;
%"GND"
"1","(-1375,4525)","0","pure_quanta_power","I57";
;
SIZE"1B"
CDS_LIB"pure_quanta_power"
HDL_POWER"GND";
"A<SIZE-1..0>\NAC"13;
%"Q_CAP"
"1","(-725,5250)","2","pure_quanta","I58";
;
LOCATION"C6064"
$SEC"1"
CDS_SEC"1"
ROOM"USB3_HUB1_CYP"
VOLTAGE"25V"
TOLERANCE"10%"
MATERIAL"X7R"
PACK_TYPE"0402"
VALUE"0.1UF"
CDS_LIB"pure_quanta"
PART_NUMBER"CH4104K1B00";
"B"
$PN"2"12;
"A"
$PN"1"5;
%"Q_CAP"
"1","(-600,5250)","0","pure_quanta","I59";
;
LOCATION"C6065"
$SEC"1"
CDS_SEC"1"
PACK_TYPE"C0402"
ROOM"USB3_HUB1_CYP"
VALUE"1UF"
MATERIAL"X6S"
VOLTAGE"25V"
TOLERANCE"10%"
CDS_LIB"pure_quanta"
PART_NUMBER"CH5104KEB02";
"B"
$PN"2"12;
"A"
$PN"1"5;
%"Q_CAP"
"1","(-325,5250)","0","pure_quanta","I60";
;
LOCATION"C6066"
$SEC"1"
CDS_SEC"1"
ROOM"USB3_HUB1_CYP"
PACK_TYPE"C0603"
MATERIAL"X6S"
TOLERANCE"20%"
VOLTAGE"6.3V"
VALUE"22UF"
CDS_LIB"pure_quanta"
PART_NUMBER"CH6221ME900";
"B"
$PN"2"12;
"A"
$PN"1"5;
%"GND"
"1","(-325,4825)","0","pure_quanta_power","I61";
;
SIZE"1B"
CDS_LIB"pure_quanta_power"
HDL_POWER"GND";
"A<SIZE-1..0>\NAC"12;
%"GND"
"1","(-3200,3025)","0","pure_quanta_power","I62";
;
CDS_LIB"pure_quanta_power"
SIZE"1B"
HDL_POWER"GND";
"A<SIZE-1..0>\NAC"11;
%"Q_CAP"
"1","(-3250,3350)","0","pure_quanta","I63";
;
LOCATION"C6069"
$SEC"1"
CDS_SEC"1"
VOLTAGE"50V"
MATERIAL"X7R"
PACK_TYPE"C0402"
TOLERANCE"10%"
VALUE"0.001UF"
ROOM"USB3_HUB1_CYP"
CDS_LIB"pure_quanta"
PART_NUMBER"CH30106KB19";
"B"
$PN"2"11;
"A"
$PN"1"4;
%"Q_CAP"
"1","(-325,3750)","0","pure_quanta","I64";
;
LOCATION"C6079"
$SEC"1"
CDS_SEC"1"
ROOM"USB3_HUB1_CYP"
PACK_TYPE"C0603"
VALUE"22UF"
VOLTAGE"6.3V"
TOLERANCE"20%"
MATERIAL"X6S"
CDS_LIB"pure_quanta"
PART_NUMBER"CH6221ME900";
"B"
$PN"2"10;
"A"
$PN"1"4;
%"Q_CAP"
"1","(-600,3750)","0","pure_quanta","I65";
;
LOCATION"C6078"
$SEC"1"
CDS_SEC"1"
ROOM"USB3_HUB1_CYP"
PACK_TYPE"C0402"
MATERIAL"X6S"
VALUE"1UF"
TOLERANCE"10%"
VOLTAGE"25V"
CDS_LIB"pure_quanta"
PART_NUMBER"CH5104KEB02";
"B"
$PN"2"10;
"A"
$PN"1"4;
%"Q_CAP"
"1","(-725,3750)","2","pure_quanta","I66";
;
LOCATION"C6077"
$SEC"1"
CDS_SEC"1"
ROOM"USB3_HUB1_CYP"
TOLERANCE"10%"
VOLTAGE"25V"
MATERIAL"X7R"
VALUE"0.1UF"
PACK_TYPE"0402"
CDS_LIB"pure_quanta"
PART_NUMBER"CH4104K1B00";
"B"
$PN"2"10;
"A"
$PN"1"4;
%"GND"
"1","(-325,3325)","0","pure_quanta_power","I67";
;
CDS_LIB"pure_quanta_power"
SIZE"1B"
HDL_POWER"GND";
"A<SIZE-1..0>\NAC"10;
%"Q_CAP"
"1","(-1175,3350)","0","pure_quanta","I68";
;
LOCATION"C6076"
$SEC"1"
CDS_SEC"1"
ROOM"USB3_HUB1_CYP"
VALUE"0.01UF"
MATERIAL"X7R"
TOLERANCE"10%"
VOLTAGE"50V"
PACK_TYPE"C0402"
CDS_LIB"pure_quanta"
PART_NUMBER"CH31006KB18";
"B"
$PN"2"9;
"A"
$PN"1"4;
%"Q_CAP"
"1","(-1425,3350)","0","pure_quanta","I69";
;
LOCATION"C6075"
$SEC"1"
CDS_SEC"1"
ROOM"USB3_HUB1_CYP"
PACK_TYPE"C0402"
VALUE"0.001UF"
TOLERANCE"10%"
MATERIAL"X7R"
VOLTAGE"50V"
CDS_LIB"pure_quanta"
PART_NUMBER"CH30106KB19";
"B"
$PN"2"9;
"A"
$PN"1"4;
%"Q_CAP"
"1","(-6425,3900)","0","pure_quanta","I7";
;
LOCATION"C6041"
$SEC"1"
CDS_SEC"1"
PACK_TYPE"0402"
MATERIAL"X7R"
TOLERANCE"10%"
VALUE"0.1UF"
VOLTAGE"25V"
ROOM"USB3_HUB1_CYP"
CDS_LIB"pure_quanta"
PART_NUMBER"CH4104K1B00";
"B"
$PN"2"7;
"A"
$PN"1"27;
%"GND"
"1","(-1375,3025)","0","pure_quanta_power","I70";
;
CDS_LIB"pure_quanta_power"
SIZE"1B"
HDL_POWER"GND";
"A<SIZE-1..0>\NAC"9;
%"Q_CAP"
"1","(-1775,3350)","0","pure_quanta","I71";
;
LOCATION"C6074"
$SEC"1"
CDS_SEC"1"
PACK_TYPE"C0402"
ROOM"USB3_HUB1_CYP"
TOLERANCE"10%"
MATERIAL"X7R"
VOLTAGE"50V"
VALUE"0.01UF"
CDS_LIB"pure_quanta"
PART_NUMBER"CH31006KB18";
"B"
$PN"2"31;
"A"
$PN"1"4;
%"GND"
"1","(-1975,3025)","0","pure_quanta_power","I72";
;
CDS_LIB"pure_quanta_power"
SIZE"1B"
HDL_POWER"GND";
"A<SIZE-1..0>\NAC"31;
%"Q_CAP"
"1","(-2025,3350)","0","pure_quanta","I73";
;
LOCATION"C6073"
$SEC"1"
CDS_SEC"1"
ROOM"USB3_HUB1_CYP"
VALUE"0.001UF"
MATERIAL"X7R"
TOLERANCE"10%"
VOLTAGE"50V"
PACK_TYPE"C0402"
CDS_LIB"pure_quanta"
PART_NUMBER"CH30106KB19";
"B"
$PN"2"31;
"A"
$PN"1"4;
%"Q_CAP"
"1","(-2400,3350)","0","pure_quanta","I74";
;
LOCATION"C6072"
$SEC"1"
CDS_SEC"1"
TOLERANCE"10%"
PACK_TYPE"C0402"
MATERIAL"X7R"
VOLTAGE"50V"
VALUE"0.01UF"
ROOM"USB3_HUB1_CYP"
CDS_LIB"pure_quanta"
PART_NUMBER"CH31006KB18";
"B"
$PN"2"8;
"A"
$PN"1"4;
%"Q_CAP"
"1","(-2650,3350)","0","pure_quanta","I75";
;
LOCATION"C6071"
$SEC"1"
CDS_SEC"1"
MATERIAL"X7R"
TOLERANCE"10%"
VOLTAGE"50V"
VALUE"0.001UF"
PACK_TYPE"C0402"
ROOM"USB3_HUB1_CYP"
CDS_LIB"pure_quanta"
PART_NUMBER"CH30106KB19";
"B"
$PN"2"8;
"A"
$PN"1"4;
%"Q_CAP"
"1","(-3000,3350)","0","pure_quanta","I76";
;
LOCATION"C6070"
$SEC"1"
CDS_SEC"1"
MATERIAL"X7R"
PACK_TYPE"C0402"
TOLERANCE"10%"
VOLTAGE"50V"
VALUE"0.01UF"
ROOM"USB3_HUB1_CYP"
CDS_LIB"pure_quanta"
PART_NUMBER"CH31006KB18";
"B"
$PN"2"11;
"A"
$PN"1"4;
%"GND"
"1","(-2600,3025)","0","pure_quanta_power","I77";
;
CDS_LIB"pure_quanta_power"
SIZE"1B"
HDL_POWER"GND";
"A<SIZE-1..0>\NAC"8;
%"Q_CAP"
"1","(-3500,3350)","0","pure_quanta","I78";
;
LOCATION"C6068"
$SEC"1"
CDS_SEC"1"
PACK_TYPE"C0402"
MATERIAL"X7R"
TOLERANCE"10%"
VOLTAGE"50V"
VALUE"0.01UF"
ROOM"USB3_HUB1_CYP"
CDS_LIB"pure_quanta"
PART_NUMBER"CH31006KB18";
"B"
$PN"2"6;
"A"
$PN"1"4;
%"Q_CAP"
"1","(-3750,3350)","0","pure_quanta","I79";
;
LOCATION"C6067"
$SEC"1"
CDS_SEC"1"
MATERIAL"X7R"
VOLTAGE"50V"
TOLERANCE"10%"
VALUE"0.001UF"
PACK_TYPE"C0402"
ROOM"USB3_HUB1_CYP"
CDS_LIB"pure_quanta"
PART_NUMBER"CH30106KB19";
"B"
$PN"2"6;
"A"
$PN"1"4;
%"GND"
"1","(-6550,3525)","0","pure_quanta_power","I8";
;
CDS_LIB"pure_quanta_power"
SIZE"1B"
HDL_POWER"GND";
"A<SIZE-1..0>\NAC"7;
%"GND"
"1","(-3700,3025)","0","pure_quanta_power","I80";
;
SIZE"1B"
CDS_LIB"pure_quanta_power"
HDL_POWER"GND";
"A<SIZE-1..0>\NAC"6;
%"Q_CAP"
"1","(-3700,2225)","2","pure_quanta","I81";
;
LOCATION"C6080"
$SEC"1"
CDS_SEC"1"
ROOM"USB3_HUB1_CYP"
PACK_TYPE"C0402"
VALUE"0.01UF"
VOLTAGE"50V"
MATERIAL"X7R"
TOLERANCE"10%"
CDS_LIB"pure_quanta"
PART_NUMBER"CH31006KB18";
"B"
$PN"2"3;
"A"
$PN"1"2;
%"Q_CAP"
"1","(-3275,2225)","2","pure_quanta","I82";
;
LOCATION"C6081"
$SEC"1"
CDS_SEC"1"
PACK_TYPE"0402"
MATERIAL"X7R"
TOLERANCE"10%"
VOLTAGE"25V"
VALUE"0.1UF"
ROOM"USB3_HUB1_CYP"
CDS_LIB"pure_quanta"
PART_NUMBER"CH4104K1B00";
"B"
$PN"2"3;
"A"
$PN"1"2;
%"Q_CAP"
"1","(-3100,2225)","0","pure_quanta","I83";
;
LOCATION"C6082"
$SEC"1"
CDS_SEC"1"
VALUE"1UF"
TOLERANCE"10%"
VOLTAGE"25V"
MATERIAL"X6S"
PACK_TYPE"C0402"
ROOM"USB3_HUB1_CYP"
CDS_LIB"pure_quanta"
PART_NUMBER"CH5104KEB02";
"B"
$PN"2"3;
"A"
$PN"1"2;
%"GND"
"1","(-3275,1775)","0","pure_quanta_power","I84";
;
SIZE"1B"
CDS_LIB"pure_quanta_power"
HDL_POWER"GND";
"A<SIZE-1..0>\NAC"3;
%"UNIVERSAL_POWER"
"1","(-8725,5875)","0","pure_quanta_power","I85";
;
HDL_POWER"P1V2_AUX"
BOM_COST"VR_SYSTEM"
CDS_LIB"pure_quanta_power";
"A"1;
%"UNIVERSAL_POWER"
"1","(-600,5725)","0","pure_quanta_power","I86";
;
HDL_POWER"P1V2_AUX"
BOM_COST"VR_SYSTEM"
CDS_LIB"pure_quanta_power";
"A"5;
%"UNIVERSAL_POWER"
"1","(-600,4200)","0","pure_quanta_power","I87";
;
HDL_POWER"P1V2_AUX"
BOM_COST"VR_SYSTEM"
CDS_LIB"pure_quanta_power";
"A"4;
%"UNIVERSAL_POWER"
"1","(-3275,2725)","0","pure_quanta_power","I88";
;
HDL_POWER"P1V2_AUX"
BOM_COST"VR_SYSTEM"
CDS_LIB"pure_quanta_power";
"A"2;
%"Q_CAP"
"1","(-7450,3200)","0","pure_quanta","I9";
;
LOCATION"C6042"
$SEC"1"
CDS_SEC"1"
PACK_TYPE"C0603"
MATERIAL"X6S"
TOLERANCE"20%"
VOLTAGE"6.3V"
VALUE"22UF"
ROOM"USB3_HUB1_CYP"
CDS_LIB"pure_quanta"
PART_NUMBER"CH6221ME900";
"B"
$PN"2"30;
"A"
$PN"1"19;
END.
